(kicad_pcb
	(version 20260206)
	(generator "pcbnew")
	(generator_version "10.0")
	(general
		(thickness 1.6)
		(legacy_teardrops no)
	)
	(paper "A4")
	(title_block
		(title "Wiwynn_Tioga_Pass_MB.brd")
		(comment 1 "Tioga Pass / footprints 407-414 of 4770")
	)
	(layers
		(0 "F.Cu" signal "TOP")
		(4 "In1.Cu" signal "L2GND")
		(6 "In2.Cu" signal "L3")
		(8 "In3.Cu" signal "L4GND")
		(10 "In4.Cu" signal "L5")
		(12 "In5.Cu" signal "L6GND")
		(14 "In6.Cu" signal "L7VCC")
		(16 "In7.Cu" signal "L8VCC")
		(18 "In8.Cu" signal "L9GND")
		(20 "In9.Cu" signal "L10")
		(22 "In10.Cu" signal "L11GND")
		(24 "In11.Cu" signal "L12")
		(26 "In12.Cu" signal "L13GND")
		(2 "B.Cu" signal "BOTTOM")
		(9 "F.Adhes" user "F.Adhesive")
		(11 "B.Adhes" user "B.Adhesive")
		(13 "F.Paste" user "Package Geometry/Pastemask Top")
		(15 "B.Paste" user "Package Geometry/Pastemask Bottom")
		(5 "F.SilkS" user "Ref Des/Silkscreen Top")
		(7 "B.SilkS" user "Ref Des/Silkscreen Bottom")
		(1 "F.Mask" user "Board Geometry/Soldermask Top")
		(3 "B.Mask" user "Board Geometry/Soldermask Bottom")
		(17 "Dwgs.User" user "User.Drawings")
		(19 "Cmts.User" user "User.Comments")
		(21 "Eco1.User" user "User.Eco1")
		(23 "Eco2.User" user "User.Eco2")
		(25 "Edge.Cuts" user "Board Geometry/Outline")
		(27 "Margin" user)
		(31 "F.CrtYd" user "Package Geometry/Place Bound Top")
		(29 "B.CrtYd" user "Package Geometry/Place Bound Bottom")
		(35 "F.Fab" user "Ref Des/Assembly Top")
		(33 "B.Fab" user "Ref Des/Assembly Bottom")
	)
	(footprint ""
		(layer "F.Cu")
		(at 183.769 -61.976 180)
		(property "Reference" "R4E10"
			(at 0 0 180)
			(layer "F.SilkS")
			(hide yes)
			(effects
				(font
					(size 1.27 1.27)
				)
			)
		)
		(property "Value" ""
			(at 0 0 180)
			(layer "F.Fab")
			(effects
				(font
					(size 1.27 1.27)
				)
			)
		)
		(duplicate_pad_numbers_are_jumpers no)
		(fp_rect
			(start 0.2794 -0.1016)
			(end -0.2794 0.9906)
			(stroke
				(width 0)
				(type default)
			)
			(fill no)
			(layer "F.CrtYd")
		)
		(fp_line
			(start 0.2794 0.9906)
			(end 0.2794 -0.1016)
			(stroke
				(width 0.1)
				(type default)
			)
			(layer "F.Fab")
		)
		(fp_line
			(start 0.2794 -0.1016)
			(end -0.2794 -0.1016)
			(stroke
				(width 0.1)
				(type default)
			)
			(layer "F.Fab")
		)
		(fp_line
			(start -0.2794 0.9906)
			(end 0.2794 0.9906)
			(stroke
				(width 0.1)
				(type default)
			)
			(layer "F.Fab")
		)
		(fp_line
			(start -0.2794 -0.1016)
			(end -0.2794 0.9906)
			(stroke
				(width 0.1)
				(type default)
			)
			(layer "F.Fab")
		)
		(pad "1" smd rect
			(at 0 0 180)
			(size 0.508 0.508)
			(layers "F.Cu" "F.Mask" "F.Paste")
			(net "PVCCIO_CPU0")
		)
		(pad "2" smd rect
			(at 0 0.889 180)
			(size 0.508 0.508)
			(layers "F.Cu" "F.Mask" "F.Paste")
			(net "SVID_DIO0_CPU0_R")
		)
		(zone
			(layer "F.Cu")
			(hatch none 0.5)
			(connect_pads
				(clearance 0)
			)
			(min_thickness 0.25)
			(keepout
				(tracks allowed)
				(vias not_allowed)
				(pads allowed)
				(copperpour not_allowed)
				(footprints allowed)
			)
			(placement
				(enabled no)
				(sheetname "")
			)
			(fill
				(thermal_gap 0.5)
				(thermal_bridge_width 0.5)
				(island_removal_mode 0)
			)
			(polygon
				(pts
					(xy 183.515 -62.23) (xy 184.023 -62.23) (xy 184.023 -62.611) (xy 183.515 -62.611)
				)
			)
		)
		(zone
			(layer "F.Cu")
			(hatch none 0.5)
			(connect_pads
				(clearance 0)
			)
			(min_thickness 0.25)
			(keepout
				(tracks not_allowed)
				(vias allowed)
				(pads allowed)
				(copperpour not_allowed)
				(footprints allowed)
			)
			(placement
				(enabled no)
				(sheetname "")
			)
			(fill
				(thermal_gap 0.5)
				(thermal_bridge_width 0.5)
				(island_removal_mode 0)
			)
			(polygon
				(pts
					(xy 183.515 -62.23) (xy 184.023 -62.23) (xy 184.023 -62.611) (xy 183.515 -62.611)
				)
			)
		)
	)
	(footprint ""
		(layer "F.Cu")
		(at 487.970576 -30.186376)
		(property "Reference" "R9F64"
			(at 0 0 0)
			(layer "F.SilkS")
			(hide yes)
			(effects
				(font
					(size 1.27 1.27)
				)
			)
		)
		(property "Value" ""
			(at 0 0 0)
			(layer "F.Fab")
			(effects
				(font
					(size 1.27 1.27)
				)
			)
		)
		(duplicate_pad_numbers_are_jumpers no)
		(fp_poly
			(pts
				(xy -0.2794 -0.1016) (xy 0.2794 -0.1016) (xy 0.2794 0.9906) (xy -0.2794 0.9906)
			)
			(stroke
				(width 0)
				(type default)
			)
			(fill no)
			(layer "F.CrtYd")
		)
		(fp_line
			(start -0.2794 -0.1016)
			(end -0.2794 0.9906)
			(stroke
				(width 0.1)
				(type default)
			)
			(layer "F.Fab")
		)
		(fp_line
			(start -0.2794 0.9906)
			(end 0.2794 0.9906)
			(stroke
				(width 0.1)
				(type default)
			)
			(layer "F.Fab")
		)
		(fp_line
			(start 0.2794 -0.1016)
			(end -0.2794 -0.1016)
			(stroke
				(width 0.1)
				(type default)
			)
			(layer "F.Fab")
		)
		(fp_line
			(start 0.2794 0.9906)
			(end 0.2794 -0.1016)
			(stroke
				(width 0.1)
				(type default)
			)
			(layer "F.Fab")
		)
		(pad "1" smd rect
			(at 0 0)
			(size 0.508 0.508)
			(layers "F.Cu" "F.Mask" "F.Paste")
			(net "SP2_BMC_CM_UART_TX_R1")
		)
		(pad "2" smd rect
			(at 0 0.889)
			(size 0.508 0.508)
			(layers "F.Cu" "F.Mask" "F.Paste")
			(net "SPA_MID_DBG_RX_R")
		)
		(zone
			(layer "F.Cu")
			(hatch none 0.5)
			(connect_pads
				(clearance 0)
			)
			(min_thickness 0.25)
			(keepout
				(tracks allowed)
				(vias not_allowed)
				(pads allowed)
				(copperpour not_allowed)
				(footprints allowed)
			)
			(placement
				(enabled no)
				(sheetname "")
			)
			(fill
				(thermal_gap 0.5)
				(thermal_bridge_width 0.5)
				(island_removal_mode 0)
			)
			(polygon
				(pts
					(xy 487.716576 -29.932376) (xy 488.224576 -29.932376) (xy 488.224576 -29.551376) (xy 487.716576 -29.551376)
				)
			)
		)
		(zone
			(layer "F.Cu")
			(hatch none 0.5)
			(connect_pads
				(clearance 0)
			)
			(min_thickness 0.25)
			(keepout
				(tracks not_allowed)
				(vias allowed)
				(pads allowed)
				(copperpour not_allowed)
				(footprints allowed)
			)
			(placement
				(enabled no)
				(sheetname "")
			)
			(fill
				(thermal_gap 0.5)
				(thermal_bridge_width 0.5)
				(island_removal_mode 0)
			)
			(polygon
				(pts
					(xy 487.716576 -29.551376) (xy 488.224576 -29.551376) (xy 488.224576 -29.932376) (xy 487.716576 -29.932376)
				)
			)
		)
	)
	(footprint ""
		(layer "F.Cu")
		(at 110.908592 -77.429614)
		(property "Reference" "C3D13"
			(at 0 0 0)
			(layer "F.SilkS")
			(hide yes)
			(effects
				(font
					(size 1.27 1.27)
				)
			)
		)
		(property "Value" ""
			(at 0 0 0)
			(layer "F.Fab")
			(effects
				(font
					(size 1.27 1.27)
				)
			)
		)
		(duplicate_pad_numbers_are_jumpers no)
		(fp_poly
			(pts
				(xy -0.4953 -0.2032) (xy 0.4953 -0.2032) (xy 0.4953 1.6002) (xy -0.4953 1.6002)
			)
			(stroke
				(width 0)
				(type default)
			)
			(fill no)
			(layer "F.CrtYd")
		)
		(fp_line
			(start -0.4953 -0.2032)
			(end 0.4953 -0.2032)
			(stroke
				(width 0.1)
				(type default)
			)
			(layer "F.Fab")
		)
		(fp_line
			(start -0.4953 1.6002)
			(end -0.4953 -0.2032)
			(stroke
				(width 0.1)
				(type default)
			)
			(layer "F.Fab")
		)
		(fp_line
			(start 0.4953 -0.2032)
			(end 0.4953 1.6002)
			(stroke
				(width 0.1)
				(type default)
			)
			(layer "F.Fab")
		)
		(fp_line
			(start 0.4953 1.6002)
			(end -0.4953 1.6002)
			(stroke
				(width 0.1)
				(type default)
			)
			(layer "F.Fab")
		)
		(pad "1" smd rect
			(at 0 0)
			(size 0.762 0.889)
			(layers "F.Cu" "F.Mask" "F.Paste")
			(net "PVCCMCP_CPU1")
		)
		(pad "2" smd rect
			(at 0 1.397)
			(size 0.762 0.889)
			(layers "F.Cu" "F.Mask" "F.Paste")
			(net "GND")
		)
		(zone
			(layer "F.Cu")
			(hatch none 0.5)
			(connect_pads
				(clearance 0)
			)
			(min_thickness 0.25)
			(keepout
				(tracks not_allowed)
				(vias allowed)
				(pads allowed)
				(copperpour not_allowed)
				(footprints allowed)
			)
			(placement
				(enabled no)
				(sheetname "")
			)
			(fill
				(thermal_gap 0.5)
				(thermal_bridge_width 0.5)
				(island_removal_mode 0)
			)
			(polygon
				(pts
					(xy 110.527592 -76.985114) (xy 111.289592 -76.985114) (xy 111.289592 -76.477114) (xy 110.527592 -76.477114)
				)
			)
		)
	)
	(footprint ""
		(layer "F.Cu")
		(at 320.6115 -124.587 90)
		(property "Reference" "C6B4"
			(at -0.8382 -0.67818 90)
			(unlocked yes)
			(layer "F.SilkS")
			(effects
				(font
					(size 0.4064 0.254)
					(thickness 0.1524)
				)
				(justify left)
			)
		)
		(property "Value" ""
			(at 0 0 90)
			(layer "F.Fab")
			(effects
				(font
					(size 1.27 1.27)
				)
			)
		)
		(duplicate_pad_numbers_are_jumpers no)
		(fp_poly
			(pts
				(xy 0.3048 -0.1016) (xy 0.3048 0.9906) (xy -0.3048 0.9906) (xy -0.3048 -0.1016)
			)
			(stroke
				(width 0)
				(type default)
			)
			(fill no)
			(layer "F.CrtYd")
		)
		(fp_line
			(start 0.3048 -0.1016)
			(end -0.3048 -0.1016)
			(stroke
				(width 0.1)
				(type default)
			)
			(layer "F.Fab")
		)
		(fp_line
			(start -0.3048 -0.1016)
			(end -0.3048 0.9906)
			(stroke
				(width 0.1)
				(type default)
			)
			(layer "F.Fab")
		)
		(fp_line
			(start 0.3048 0.9906)
			(end 0.3048 -0.1016)
			(stroke
				(width 0.1)
				(type default)
			)
			(layer "F.Fab")
		)
		(fp_line
			(start -0.3048 0.9906)
			(end 0.3048 0.9906)
			(stroke
				(width 0.1)
				(type default)
			)
			(layer "F.Fab")
		)
		(pad "1" smd rect
			(at 0 0 90)
			(size 0.508 0.508)
			(layers "F.Cu" "F.Mask" "F.Paste")
			(net "P3E_CPU0_PE1_PCH_TXN<15>")
		)
		(pad "2" smd rect
			(at 0 0.889 90)
			(size 0.508 0.508)
			(layers "F.Cu" "F.Mask" "F.Paste")
			(net "P3E_CPU0_PE1_PCH_C_TXN<15>")
		)
		(zone
			(layer "F.Cu")
			(hatch none 0.5)
			(connect_pads
				(clearance 0)
			)
			(min_thickness 0.25)
			(keepout
				(tracks allowed)
				(vias not_allowed)
				(pads allowed)
				(copperpour not_allowed)
				(footprints allowed)
			)
			(placement
				(enabled no)
				(sheetname "")
			)
			(fill
				(thermal_gap 0.5)
				(thermal_bridge_width 0.5)
				(island_removal_mode 0)
			)
			(polygon
				(pts
					(xy 320.8655 -124.333) (xy 320.8655 -124.841) (xy 321.2465 -124.841) (xy 321.2465 -124.333)
				)
			)
		)
		(zone
			(layer "F.Cu")
			(hatch none 0.5)
			(connect_pads
				(clearance 0)
			)
			(min_thickness 0.25)
			(keepout
				(tracks not_allowed)
				(vias allowed)
				(pads allowed)
				(copperpour not_allowed)
				(footprints allowed)
			)
			(placement
				(enabled no)
				(sheetname "")
			)
			(fill
				(thermal_gap 0.5)
				(thermal_bridge_width 0.5)
				(island_removal_mode 0)
			)
			(polygon
				(pts
					(xy 321.2465 -124.333) (xy 321.2465 -124.841) (xy 320.8655 -124.841) (xy 320.8655 -124.333)
				)
			)
		)
	)
	(footprint ""
		(layer "F.Cu")
		(at 17.526 -86.8172 180)
		(property "Reference" "R1D9"
			(at 0 0 180)
			(layer "F.SilkS")
			(hide yes)
			(effects
				(font
					(size 1.27 1.27)
				)
			)
		)
		(property "Value" ""
			(at 0 0 180)
			(layer "F.Fab")
			(effects
				(font
					(size 1.27 1.27)
				)
			)
		)
		(duplicate_pad_numbers_are_jumpers no)
		(fp_rect
			(start 0.2794 -0.1016)
			(end -0.2794 0.9906)
			(stroke
				(width 0)
				(type default)
			)
			(fill no)
			(layer "F.CrtYd")
		)
		(fp_line
			(start 0.2794 0.9906)
			(end 0.2794 -0.1016)
			(stroke
				(width 0.1)
				(type default)
			)
			(layer "F.Fab")
		)
		(fp_line
			(start 0.2794 -0.1016)
			(end -0.2794 -0.1016)
			(stroke
				(width 0.1)
				(type default)
			)
			(layer "F.Fab")
		)
		(fp_line
			(start -0.2794 0.9906)
			(end 0.2794 0.9906)
			(stroke
				(width 0.1)
				(type default)
			)
			(layer "F.Fab")
		)
		(fp_line
			(start -0.2794 -0.1016)
			(end -0.2794 0.9906)
			(stroke
				(width 0.1)
				(type default)
			)
			(layer "F.Fab")
		)
		(pad "1" smd rect
			(at 0 0 180)
			(size 0.508 0.508)
			(layers "F.Cu" "F.Mask" "F.Paste")
			(net "SVID_CLK0_CPU1_R")
		)
		(pad "2" smd rect
			(at 0 0.889 180)
			(size 0.508 0.508)
			(layers "F.Cu" "F.Mask" "F.Paste")
			(net "SVID_VCLK_PVCCIN_CPU1")
		)
		(zone
			(layer "F.Cu")
			(hatch none 0.5)
			(connect_pads
				(clearance 0)
			)
			(min_thickness 0.25)
			(keepout
				(tracks not_allowed)
				(vias allowed)
				(pads allowed)
				(copperpour not_allowed)
				(footprints allowed)
			)
			(placement
				(enabled no)
				(sheetname "")
			)
			(fill
				(thermal_gap 0.5)
				(thermal_bridge_width 0.5)
				(island_removal_mode 0)
			)
			(polygon
				(pts
					(xy 17.272 -87.0712) (xy 17.78 -87.0712) (xy 17.78 -87.4522) (xy 17.272 -87.4522)
				)
			)
		)
		(zone
			(layer "F.Cu")
			(hatch none 0.5)
			(connect_pads
				(clearance 0)
			)
			(min_thickness 0.25)
			(keepout
				(tracks allowed)
				(vias not_allowed)
				(pads allowed)
				(copperpour not_allowed)
				(footprints allowed)
			)
			(placement
				(enabled no)
				(sheetname "")
			)
			(fill
				(thermal_gap 0.5)
				(thermal_bridge_width 0.5)
				(island_removal_mode 0)
			)
			(polygon
				(pts
					(xy 17.272 -87.0712) (xy 17.78 -87.0712) (xy 17.78 -87.4522) (xy 17.272 -87.4522)
				)
			)
		)
	)
	(footprint ""
		(layer "F.Cu")
		(at 24.1554 -41.2242 -90)
		(property "Reference" "R1E12"
			(at 0 0 270)
			(layer "F.SilkS")
			(hide yes)
			(effects
				(font
					(size 1.27 1.27)
				)
			)
		)
		(property "Value" ""
			(at 0 0 270)
			(layer "F.Fab")
			(effects
				(font
					(size 1.27 1.27)
				)
			)
		)
		(duplicate_pad_numbers_are_jumpers no)
		(fp_rect
			(start 0.2794 0.9906)
			(end -0.2794 -0.1016)
			(stroke
				(width 0)
				(type default)
			)
			(fill no)
			(layer "F.CrtYd")
		)
		(fp_line
			(start -0.2794 0.9906)
			(end 0.2794 0.9906)
			(stroke
				(width 0.1)
				(type default)
			)
			(layer "F.Fab")
		)
		(fp_line
			(start 0.2794 0.9906)
			(end 0.2794 -0.1016)
			(stroke
				(width 0.1)
				(type default)
			)
			(layer "F.Fab")
		)
		(fp_line
			(start -0.2794 -0.1016)
			(end -0.2794 0.9906)
			(stroke
				(width 0.1)
				(type default)
			)
			(layer "F.Fab")
		)
		(fp_line
			(start 0.2794 -0.1016)
			(end -0.2794 -0.1016)
			(stroke
				(width 0.1)
				(type default)
			)
			(layer "F.Fab")
		)
		(pad "1" smd rect
			(at 0 0 270)
			(size 0.508 0.508)
			(layers "F.Cu" "F.Mask" "F.Paste")
			(net "P5V_STBY")
		)
		(pad "2" smd rect
			(at 0 0.889 270)
			(size 0.508 0.508)
			(layers "F.Cu" "F.Mask" "F.Paste")
			(net "FAN_PWM_OUT_SYS0_R")
		)
		(zone
			(layer "F.Cu")
			(hatch none 0.5)
			(connect_pads
				(clearance 0)
			)
			(min_thickness 0.25)
			(keepout
				(tracks not_allowed)
				(vias allowed)
				(pads allowed)
				(copperpour not_allowed)
				(footprints allowed)
			)
			(placement
				(enabled no)
				(sheetname "")
			)
			(fill
				(thermal_gap 0.5)
				(thermal_bridge_width 0.5)
				(island_removal_mode 0)
			)
			(polygon
				(pts
					(xy 23.5204 -40.9702) (xy 23.9014 -40.9702) (xy 23.9014 -41.4782) (xy 23.5204 -41.4782)
				)
			)
		)
		(zone
			(layer "F.Cu")
			(hatch none 0.5)
			(connect_pads
				(clearance 0)
			)
			(min_thickness 0.25)
			(keepout
				(tracks allowed)
				(vias not_allowed)
				(pads allowed)
				(copperpour not_allowed)
				(footprints allowed)
			)
			(placement
				(enabled no)
				(sheetname "")
			)
			(fill
				(thermal_gap 0.5)
				(thermal_bridge_width 0.5)
				(island_removal_mode 0)
			)
			(polygon
				(pts
					(xy 23.5204 -40.9702) (xy 23.9014 -40.9702) (xy 23.9014 -41.4782) (xy 23.5204 -41.4782)
				)
			)
		)
	)
	(footprint ""
		(layer "F.Cu")
		(at 178.689 -66.548 90)
		(property "Reference" "R4D58"
			(at 0 0 90)
			(layer "F.SilkS")
			(hide yes)
			(effects
				(font
					(size 1.27 1.27)
				)
			)
		)
		(property "Value" ""
			(at 0 0 90)
			(layer "F.Fab")
			(effects
				(font
					(size 1.27 1.27)
				)
			)
		)
		(duplicate_pad_numbers_are_jumpers no)
		(fp_rect
			(start -0.2794 -0.1016)
			(end 0.2794 0.9906)
			(stroke
				(width 0)
				(type default)
			)
			(fill no)
			(layer "F.CrtYd")
		)
		(fp_line
			(start 0.2794 -0.1016)
			(end -0.2794 -0.1016)
			(stroke
				(width 0.1)
				(type default)
			)
			(layer "F.Fab")
		)
		(fp_line
			(start -0.2794 -0.1016)
			(end -0.2794 0.9906)
			(stroke
				(width 0.1)
				(type default)
			)
			(layer "F.Fab")
		)
		(fp_line
			(start 0.2794 0.9906)
			(end 0.2794 -0.1016)
			(stroke
				(width 0.1)
				(type default)
			)
			(layer "F.Fab")
		)
		(fp_line
			(start -0.2794 0.9906)
			(end 0.2794 0.9906)
			(stroke
				(width 0.1)
				(type default)
			)
			(layer "F.Fab")
		)
		(pad "1" smd rect
			(at 0 0 90)
			(size 0.508 0.508)
			(layers "F.Cu" "F.Mask" "F.Paste")
			(net "P3V3_STBY")
		)
		(pad "2" smd rect
			(at 0 0.889 90)
			(size 0.508 0.508)
			(layers "F.Cu" "F.Mask" "F.Paste")
			(net "VR_VRRDY_PVCCIN_CPU0")
		)
		(zone
			(layer "F.Cu")
			(hatch none 0.5)
			(connect_pads
				(clearance 0)
			)
			(min_thickness 0.25)
			(keepout
				(tracks not_allowed)
				(vias allowed)
				(pads allowed)
				(copperpour not_allowed)
				(footprints allowed)
			)
			(placement
				(enabled no)
				(sheetname "")
			)
			(fill
				(thermal_gap 0.5)
				(thermal_bridge_width 0.5)
				(island_removal_mode 0)
			)
			(polygon
				(pts
					(xy 178.943 -66.294) (xy 179.324 -66.294) (xy 179.324 -66.802) (xy 178.943 -66.802)
				)
			)
		)
		(zone
			(layer "F.Cu")
			(hatch none 0.5)
			(connect_pads
				(clearance 0)
			)
			(min_thickness 0.25)
			(keepout
				(tracks allowed)
				(vias not_allowed)
				(pads allowed)
				(copperpour not_allowed)
				(footprints allowed)
			)
			(placement
				(enabled no)
				(sheetname "")
			)
			(fill
				(thermal_gap 0.5)
				(thermal_bridge_width 0.5)
				(island_removal_mode 0)
			)
			(polygon
				(pts
					(xy 178.943 -66.294) (xy 179.324 -66.294) (xy 179.324 -66.802) (xy 178.943 -66.802)
				)
			)
		)
	)
	(footprint ""
		(layer "F.Cu")
		(at 413.3215 -112.649 -90)
		(property "Reference" "R2T29"
			(at 0 0 270)
			(layer "F.SilkS")
			(hide yes)
			(effects
				(font
					(size 1.27 1.27)
				)
			)
		)
		(property "Value" ""
			(at 0 0 270)
			(layer "F.Fab")
			(effects
				(font
					(size 1.27 1.27)
				)
			)
		)
		(duplicate_pad_numbers_are_jumpers no)
		(fp_poly
			(pts
				(xy -0.2794 -0.1016) (xy 0.2794 -0.1016) (xy 0.2794 0.9906) (xy -0.2794 0.9906)
			)
			(stroke
				(width 0)
				(type default)
			)
			(fill no)
			(layer "F.CrtYd")
		)
		(fp_line
			(start -0.2794 0.9906)
			(end 0.2794 0.9906)
			(stroke
				(width 0.1)
				(type default)
			)
			(layer "F.Fab")
		)
		(fp_line
			(start 0.2794 0.9906)
			(end 0.2794 -0.1016)
			(stroke
				(width 0.1)
				(type default)
			)
			(layer "F.Fab")
		)
		(fp_line
			(start -0.2794 -0.1016)
			(end -0.2794 0.9906)
			(stroke
				(width 0.1)
				(type default)
			)
			(layer "F.Fab")
		)
		(fp_line
			(start 0.2794 -0.1016)
			(end -0.2794 -0.1016)
			(stroke
				(width 0.1)
				(type default)
			)
			(layer "F.Fab")
		)
		(pad "1" smd rect
			(at 0 0 270)
			(size 0.508 0.508)
			(layers "F.Cu" "F.Mask" "F.Paste")
			(net "P3V3_STBY")
		)
		(pad "2" smd rect
			(at 0 0.889 270)
			(size 0.508 0.508)
			(layers "F.Cu" "F.Mask" "F.Paste")
			(net "IRQ_OOB_MGMT_RISER_ALERT_N")
		)
		(zone
			(layer "F.Cu")
			(hatch none 0.5)
			(connect_pads
				(clearance 0)
			)
			(min_thickness 0.25)
			(keepout
				(tracks not_allowed)
				(vias allowed)
				(pads allowed)
				(copperpour not_allowed)
				(footprints allowed)
			)
			(placement
				(enabled no)
				(sheetname "")
			)
			(fill
				(thermal_gap 0.5)
				(thermal_bridge_width 0.5)
				(island_removal_mode 0)
			)
			(polygon
				(pts
					(xy 412.6865 -112.903) (xy 412.6865 -112.395) (xy 413.0675 -112.395) (xy 413.0675 -112.903)
				)
			)
		)
		(zone
			(layer "F.Cu")
			(hatch none 0.5)
			(connect_pads
				(clearance 0)
			)
			(min_thickness 0.25)
			(keepout
				(tracks allowed)
				(vias not_allowed)
				(pads allowed)
				(copperpour not_allowed)
				(footprints allowed)
			)
			(placement
				(enabled no)
				(sheetname "")
			)
			(fill
				(thermal_gap 0.5)
				(thermal_bridge_width 0.5)
				(island_removal_mode 0)
			)
			(polygon
				(pts
					(xy 413.0675 -112.903) (xy 413.0675 -112.395) (xy 412.6865 -112.395) (xy 412.6865 -112.903)
				)
			)
		)
	)
)
